(kicad_pcb
	(version 20260206)
	(generator "pcbnew")
	(generator_version "10.0")
	(general
		(thickness 1.6)
		(legacy_teardrops no)
	)
	(paper "A4")
	(title_block
		(title "v2-tray-backplane — ms_tbp_v2.brd")
		(comment 1 "Open CloudServer (Microsoft) / footprint 158 of 164 (J1), pads 96-155 of 155")
	)
	(layers
		(0 "F.Cu" signal "TOP")
		(4 "In1.Cu" signal "LYR2")
		(6 "In2.Cu" signal "LYR3")
		(8 "In3.Cu" signal "LYR4")
		(10 "In4.Cu" signal "LYR5")
		(12 "In5.Cu" signal "LYR6")
		(14 "In6.Cu" signal "LYR7")
		(2 "B.Cu" signal "BOTTOM")
		(9 "F.Adhes" user "F.Adhesive")
		(11 "B.Adhes" user "B.Adhesive")
		(13 "F.Paste" user "Package Geometry/Pastemask Top")
		(15 "B.Paste" user "Package Geometry/Pastemask Bottom")
		(5 "F.SilkS" user "Ref Des/Silkscreen Top")
		(7 "B.SilkS" user "Ref Des/Silkscreen Bottom")
		(1 "F.Mask" user "Board Geometry/Soldermask Top")
		(3 "B.Mask" user "Board Geometry/Soldermask Bottom")
		(17 "Dwgs.User" user "User.Drawings")
		(19 "Cmts.User" user "User.Comments")
		(21 "Eco1.User" user "User.Eco1")
		(23 "Eco2.User" user "User.Eco2")
		(25 "Edge.Cuts" user "Board Geometry/Outline")
		(27 "Margin" user)
		(31 "F.CrtYd" user "Package Geometry/Place Bound Top")
		(29 "B.CrtYd" user "Package Geometry/Place Bound Bottom")
		(35 "F.Fab" user "Ref Des/Assembly Top")
		(33 "B.Fab" user "Ref Des/Assembly Bottom")
	)
	(footprint ""
		(layer "F.Cu")
		(at -392.46 45.260001 180)
		(property "Reference" "J1"
			(at 9 24.584899 0)
			(unlocked yes)
			(layer "F.SilkS")
			(effects
				(font
					(size 0.762 0.5334)
					(thickness 0.1016)
				)
			)
		)
		(property "Value" ""
			(at 0 0 180)
			(layer "F.Fab")
			(effects
				(font
					(size 1.27 1.27)
				)
			)
		)
		(duplicate_pad_numbers_are_jumpers no)
		(pad "J6" thru_hole circle
			(at 10 12.5 180)
			(size 0.8128 0.8128)
			(drill 0.508)
			(layers "*.Cu" "*.Mask")
			(remove_unused_layers no)
			(net "GND")
		)
		(pad "J7" thru_hole circle
			(at 11.999999 12.6 180)
			(size 0.8128 0.8128)
			(drill 0.508)
			(layers "*.Cu" "*.Mask")
			(remove_unused_layers no)
			(net "PCIE_B2T_B1_TX_DP<1>")
		)
		(pad "J8" thru_hole circle
			(at 14 12.5 180)
			(size 0.8128 0.8128)
			(drill 0.508)
			(layers "*.Cu" "*.Mask")
			(remove_unused_layers no)
			(net "GND")
		)
		(pad "J9" thru_hole circle
			(at 16.000001 12.6 180)
			(size 0.8128 0.8128)
			(drill 0.508)
			(layers "*.Cu" "*.Mask")
			(remove_unused_layers no)
			(net "CLK_100M_B1_P<3>")
		)
		(pad "J10" thru_hole circle
			(at 18 12.5 180)
			(size 0.8128 0.8128)
			(drill 0.508)
			(layers "*.Cu" "*.Mask")
			(remove_unused_layers no)
			(net "P12V_MEZZ_B1")
		)
		(pad "K1" thru_hole circle
			(at 0 14 180)
			(size 0.8128 0.8128)
			(drill 0.508)
			(layers "*.Cu" "*.Mask")
			(remove_unused_layers no)
			(net "PCIE_B2T_B1_TX_DN<7>")
		)
		(pad "K2" thru_hole circle
			(at 2.000001 13.9 180)
			(size 0.8128 0.8128)
			(drill 0.508)
			(layers "*.Cu" "*.Mask")
			(remove_unused_layers no)
			(net "PCIE_B2T_B1_TX_DP<6>")
		)
		(pad "K3" thru_hole circle
			(at 4 14 180)
			(size 0.8128 0.8128)
			(drill 0.508)
			(layers "*.Cu" "*.Mask")
			(remove_unused_layers no)
			(net "PCIE_B2T_B1_TX_DN<5>")
		)
		(pad "K4" thru_hole circle
			(at 6.000001 13.9 180)
			(size 0.8128 0.8128)
			(drill 0.508)
			(layers "*.Cu" "*.Mask")
			(remove_unused_layers no)
			(net "PCIE_B2T_B1_TX_DP<4>")
		)
		(pad "K5" thru_hole circle
			(at 7.999999 14 180)
			(size 0.8128 0.8128)
			(drill 0.508)
			(layers "*.Cu" "*.Mask")
			(remove_unused_layers no)
			(net "PCIE_B2T_B1_TX_DN<3>")
		)
		(pad "K6" thru_hole circle
			(at 10 13.9 180)
			(size 0.8128 0.8128)
			(drill 0.508)
			(layers "*.Cu" "*.Mask")
			(remove_unused_layers no)
			(net "PCIE_B2T_B1_TX_DP<2>")
		)
		(pad "K7" thru_hole circle
			(at 11.999999 14 180)
			(size 0.8128 0.8128)
			(drill 0.508)
			(layers "*.Cu" "*.Mask")
			(remove_unused_layers no)
			(net "PCIE_B2T_B1_TX_DN<1>")
		)
		(pad "K8" thru_hole circle
			(at 14 13.9 180)
			(size 0.8128 0.8128)
			(drill 0.508)
			(layers "*.Cu" "*.Mask")
			(remove_unused_layers no)
			(net "PCIE_B2T_B1_TX_DP<0>")
		)
		(pad "K9" thru_hole circle
			(at 16.000001 14 180)
			(size 0.8128 0.8128)
			(drill 0.508)
			(layers "*.Cu" "*.Mask")
			(remove_unused_layers no)
			(net "CLK_100M_B1_N<3>")
		)
		(pad "K10" thru_hole circle
			(at 18 13.9 180)
			(size 0.8128 0.8128)
			(drill 0.508)
			(layers "*.Cu" "*.Mask")
			(remove_unused_layers no)
			(net "P12V_MEZZ_B1")
		)
		(pad "L1" thru_hole circle
			(at 0 15.4 180)
			(size 0.8128 0.8128)
			(drill 0.508)
			(layers "*.Cu" "*.Mask")
			(remove_unused_layers no)
			(net "GND")
		)
		(pad "L2" thru_hole circle
			(at 2.000001 15.3 180)
			(size 0.8128 0.8128)
			(drill 0.508)
			(layers "*.Cu" "*.Mask")
			(remove_unused_layers no)
			(net "PCIE_B2T_B1_TX_DN<6>")
		)
		(pad "L3" thru_hole circle
			(at 4 15.4 180)
			(size 0.8128 0.8128)
			(drill 0.508)
			(layers "*.Cu" "*.Mask")
			(remove_unused_layers no)
			(net "GND")
		)
		(pad "L4" thru_hole circle
			(at 6.000001 15.3 180)
			(size 0.8128 0.8128)
			(drill 0.508)
			(layers "*.Cu" "*.Mask")
			(remove_unused_layers no)
			(net "PCIE_B2T_B1_TX_DN<4>")
		)
		(pad "L5" thru_hole circle
			(at 7.999999 15.4 180)
			(size 0.8128 0.8128)
			(drill 0.508)
			(layers "*.Cu" "*.Mask")
			(remove_unused_layers no)
			(net "GND")
		)
		(pad "L6" thru_hole circle
			(at 10 15.3 180)
			(size 0.8128 0.8128)
			(drill 0.508)
			(layers "*.Cu" "*.Mask")
			(remove_unused_layers no)
			(net "PCIE_B2T_B1_TX_DN<2>")
		)
		(pad "L7" thru_hole circle
			(at 11.999999 15.4 180)
			(size 0.8128 0.8128)
			(drill 0.508)
			(layers "*.Cu" "*.Mask")
			(remove_unused_layers no)
			(net "GND")
		)
		(pad "L8" thru_hole circle
			(at 14 15.3 180)
			(size 0.8128 0.8128)
			(drill 0.508)
			(layers "*.Cu" "*.Mask")
			(remove_unused_layers no)
			(net "PCIE_B2T_B1_TX_DN<0>")
		)
		(pad "L9" thru_hole circle
			(at 16.000001 15.4 180)
			(size 0.8128 0.8128)
			(drill 0.508)
			(layers "*.Cu" "*.Mask")
			(remove_unused_layers no)
			(net "GND")
		)
		(pad "L10" thru_hole circle
			(at 18 15.3 180)
			(size 0.8128 0.8128)
			(drill 0.508)
			(layers "*.Cu" "*.Mask")
			(remove_unused_layers no)
			(net "P12V_MEZZ_B1")
		)
		(pad "M1" thru_hole circle
			(at 0 16.799999 180)
			(size 0.8128 0.8128)
			(drill 0.508)
			(layers "*.Cu" "*.Mask")
			(remove_unused_layers no)
			(net "PCIE_B2T_B1_TX_DP<15>")
		)
		(pad "M2" thru_hole circle
			(at 2.000001 16.7 180)
			(size 0.8128 0.8128)
			(drill 0.508)
			(layers "*.Cu" "*.Mask")
			(remove_unused_layers no)
			(net "GND")
		)
		(pad "M3" thru_hole circle
			(at 4 16.799999 180)
			(size 0.8128 0.8128)
			(drill 0.508)
			(layers "*.Cu" "*.Mask")
			(remove_unused_layers no)
			(net "PCIE_B2T_B1_TX_DP<13>")
		)
		(pad "M4" thru_hole circle
			(at 6.000001 16.7 180)
			(size 0.8128 0.8128)
			(drill 0.508)
			(layers "*.Cu" "*.Mask")
			(remove_unused_layers no)
			(net "GND")
		)
		(pad "M5" thru_hole circle
			(at 7.999999 16.799999 180)
			(size 0.8128 0.8128)
			(drill 0.508)
			(layers "*.Cu" "*.Mask")
			(remove_unused_layers no)
			(net "PCIE_B2T_B1_TX_DP<11>")
		)
		(pad "M6" thru_hole circle
			(at 10 16.7 180)
			(size 0.8128 0.8128)
			(drill 0.508)
			(layers "*.Cu" "*.Mask")
			(remove_unused_layers no)
			(net "GND")
		)
		(pad "M7" thru_hole circle
			(at 11.999999 16.799999 180)
			(size 0.8128 0.8128)
			(drill 0.508)
			(layers "*.Cu" "*.Mask")
			(remove_unused_layers no)
			(net "PCIE_B2T_B1_TX_DP<9>")
		)
		(pad "M8" thru_hole circle
			(at 14 16.7 180)
			(size 0.8128 0.8128)
			(drill 0.508)
			(layers "*.Cu" "*.Mask")
			(remove_unused_layers no)
			(net "GND")
		)
		(pad "M9" thru_hole circle
			(at 16.000001 16.799999 180)
			(size 0.8128 0.8128)
			(drill 0.508)
			(layers "*.Cu" "*.Mask")
			(remove_unused_layers no)
			(net "GND")
		)
		(pad "M10" thru_hole circle
			(at 18 16.7 180)
			(size 0.8128 0.8128)
			(drill 0.508)
			(layers "*.Cu" "*.Mask")
			(remove_unused_layers no)
			(net "GND")
		)
		(pad "N1" thru_hole circle
			(at 0 18.199999 180)
			(size 0.8128 0.8128)
			(drill 0.508)
			(layers "*.Cu" "*.Mask")
			(remove_unused_layers no)
			(net "PCIE_B2T_B1_TX_DN<15>")
		)
		(pad "N2" thru_hole circle
			(at 2.000001 18.099999 180)
			(size 0.8128 0.8128)
			(drill 0.508)
			(layers "*.Cu" "*.Mask")
			(remove_unused_layers no)
			(net "PCIE_B2T_B1_TX_DP<14>")
		)
		(pad "N3" thru_hole circle
			(at 4 18.199999 180)
			(size 0.8128 0.8128)
			(drill 0.508)
			(layers "*.Cu" "*.Mask")
			(remove_unused_layers no)
			(net "PCIE_B2T_B1_TX_DN<13>")
		)
		(pad "N4" thru_hole circle
			(at 6.000001 18.099999 180)
			(size 0.8128 0.8128)
			(drill 0.508)
			(layers "*.Cu" "*.Mask")
			(remove_unused_layers no)
			(net "PCIE_B2T_B1_TX_DP<12>")
		)
		(pad "N5" thru_hole circle
			(at 7.999999 18.199999 180)
			(size 0.8128 0.8128)
			(drill 0.508)
			(layers "*.Cu" "*.Mask")
			(remove_unused_layers no)
			(net "PCIE_B2T_B1_TX_DN<11>")
		)
		(pad "N6" thru_hole circle
			(at 10 18.099999 180)
			(size 0.8128 0.8128)
			(drill 0.508)
			(layers "*.Cu" "*.Mask")
			(remove_unused_layers no)
			(net "PCIE_B2T_B1_TX_DP<10>")
		)
		(pad "N7" thru_hole circle
			(at 11.999999 18.199999 180)
			(size 0.8128 0.8128)
			(drill 0.508)
			(layers "*.Cu" "*.Mask")
			(remove_unused_layers no)
			(net "PCIE_B2T_B1_TX_DN<9>")
		)
		(pad "N8" thru_hole circle
			(at 14 18.099999 180)
			(size 0.8128 0.8128)
			(drill 0.508)
			(layers "*.Cu" "*.Mask")
			(remove_unused_layers no)
			(net "PCIE_B2T_B1_TX_DP<8>")
		)
		(pad "N9" thru_hole circle
			(at 16.000001 18.199999 180)
			(size 0.8128 0.8128)
			(drill 0.508)
			(layers "*.Cu" "*.Mask")
			(remove_unused_layers no)
			(net "GND")
		)
		(pad "N10" thru_hole circle
			(at 18 18.099999 180)
			(size 0.8128 0.8128)
			(drill 0.508)
			(layers "*.Cu" "*.Mask")
			(remove_unused_layers no)
			(net "P12V_MEZZ_B1")
		)
		(pad "O1" thru_hole circle
			(at 0 19.599999 180)
			(size 0.8128 0.8128)
			(drill 0.508)
			(layers "*.Cu" "*.Mask")
			(remove_unused_layers no)
			(net "GND")
		)
		(pad "O2" thru_hole circle
			(at 2.000001 19.499999 180)
			(size 0.8128 0.8128)
			(drill 0.508)
			(layers "*.Cu" "*.Mask")
			(remove_unused_layers no)
			(net "PCIE_B2T_B1_TX_DN<14>")
		)
		(pad "O3" thru_hole circle
			(at 4 19.599999 180)
			(size 0.8128 0.8128)
			(drill 0.508)
			(layers "*.Cu" "*.Mask")
			(remove_unused_layers no)
			(net "GND")
		)
		(pad "O4" thru_hole circle
			(at 6.000001 19.499999 180)
			(size 0.8128 0.8128)
			(drill 0.508)
			(layers "*.Cu" "*.Mask")
			(remove_unused_layers no)
			(net "PCIE_B2T_B1_TX_DN<12>")
		)
		(pad "O5" thru_hole circle
			(at 7.999999 19.599999 180)
			(size 0.8128 0.8128)
			(drill 0.508)
			(layers "*.Cu" "*.Mask")
			(remove_unused_layers no)
			(net "GND")
		)
		(pad "O6" thru_hole circle
			(at 10 19.499999 180)
			(size 0.8128 0.8128)
			(drill 0.508)
			(layers "*.Cu" "*.Mask")
			(remove_unused_layers no)
			(net "PCIE_B2T_B1_TX_DN<10>")
		)
		(pad "O7" thru_hole circle
			(at 11.999999 19.599999 180)
			(size 0.8128 0.8128)
			(drill 0.508)
			(layers "*.Cu" "*.Mask")
			(remove_unused_layers no)
			(net "GND")
		)
		(pad "O8" thru_hole circle
			(at 14 19.499999 180)
			(size 0.8128 0.8128)
			(drill 0.508)
			(layers "*.Cu" "*.Mask")
			(remove_unused_layers no)
			(net "PCIE_B2T_B1_TX_DN<8>")
		)
		(pad "O9" thru_hole circle
			(at 16.000001 19.599999 180)
			(size 0.8128 0.8128)
			(drill 0.508)
			(layers "*.Cu" "*.Mask")
			(remove_unused_layers no)
			(net "GND")
		)
		(pad "O10" thru_hole circle
			(at 18 19.499999 180)
			(size 0.8128 0.8128)
			(drill 0.508)
			(layers "*.Cu" "*.Mask")
			(remove_unused_layers no)
			(net "P12V_MEZZ_B1")
		)
		(pad "P2" thru_hole circle
			(at 2.000001 20.899999 180)
			(size 0.8128 0.8128)
			(drill 0.508)
			(layers "*.Cu" "*.Mask")
			(remove_unused_layers no)
			(net "GND")
		)
		(pad "P4" thru_hole circle
			(at 6.000001 20.899999 180)
			(size 0.8128 0.8128)
			(drill 0.508)
			(layers "*.Cu" "*.Mask")
			(remove_unused_layers no)
			(net "GND")
		)
		(pad "P6" thru_hole circle
			(at 10 20.899999 180)
			(size 0.8128 0.8128)
			(drill 0.508)
			(layers "*.Cu" "*.Mask")
			(remove_unused_layers no)
			(net "GND")
		)
		(pad "P8" thru_hole circle
			(at 14 20.899999 180)
			(size 0.8128 0.8128)
			(drill 0.508)
			(layers "*.Cu" "*.Mask")
			(remove_unused_layers no)
			(net "GND")
		)
		(pad "P10" thru_hole circle
			(at 18 20.899999 180)
			(size 0.8128 0.8128)
			(drill 0.508)
			(layers "*.Cu" "*.Mask")
			(remove_unused_layers no)
			(net "GND")
		)
	)
)
